#ISCELL
  pure_quanta quanta_title_block_c *
  *
#CELL
  pure_quanta tdr_3p *
  page60_i1
#ISCELL
  logical_power universal_gnd *
  page60_i10
#CELL
  pure_quanta tdr_3p *
  page60_i11
#ISCELL
  logical_power universal_gnd *
  page60_i12
#CELL
  pure_quanta tp_tdr_4p_fts *
  page60_i13
#CELL
  pure_quanta tp_tdr_4p_fts *
  page60_i14
#CELL
  pure_quanta tp_tdr_4p_fts *
  page60_i18
#CELL
  pure_quanta tp_tdr_4p_fts *
  page60_i19
#ISCELL
  logical_power universal_gnd *
  page60_i2
#CELL
  pure_quanta tp_tdr_4p_fts *
  page60_i22
#CELL
  pure_quanta tp_tdr_4p_fts *
  page60_i23
#CELL
  pure_quanta tdr_3p *
  page60_i3
#CELL
  pure_quanta tp_tdr_4p_fts *
  page60_i34
#CELL
  pure_quanta tp_tdr_4p_fts *
  page60_i35
#CELL
  pure_quanta tp_tdr_4p_fts *
  page60_i38
#CELL
  pure_quanta tp_tdr_4p_fts *
  page60_i39
#ISCELL
  logical_power universal_gnd *
  page60_i4
#CELL
  pure_quanta tp_tdr_4p_fts *
  page60_i42
#CELL
  pure_quanta tp_tdr_4p_fts *
  page60_i43
#CELL
  pure_quanta tp_tdr_4p_fts *
  page60_i46
#CELL
  pure_quanta tp_tdr_4p_fts *
  page60_i47
#CELL
  pure_quanta tdr_3p *
  page60_i5
#CELL
  pure_quanta tp_tdr_4p_fts *
  page60_i58
#CELL
  pure_quanta tp_tdr_4p_fts *
  page60_i59
#ISCELL
  logical_power universal_gnd *
  page60_i6
#ISCELL
  logical_power universal_gnd *
  page60_i61
#ISCELL
  logical_power universal_gnd *
  page60_i62
#ISCELL
  logical_power universal_gnd *
  page60_i63
#ISCELL
  logical_power universal_gnd *
  page60_i64
#ISCELL
  logical_power universal_gnd *
  page60_i65
#ISCELL
  logical_power universal_gnd *
  page60_i66
#ISCELL
  logical_power universal_gnd *
  page60_i67
#ISCELL
  logical_power universal_gnd *
  page60_i68
#ISCELL
  logical_power universal_gnd *
  page60_i69
#CELL
  pure_quanta tdr_3p *
  page60_i7
#ISCELL
  logical_power universal_gnd *
  page60_i70
#ISCELL
  logical_power universal_gnd *
  page60_i71
#ISCELL
  logical_power universal_gnd *
  page60_i72
#ISCELL
  logical_power universal_gnd *
  page60_i73
#ISCELL
  logical_power universal_gnd *
  page60_i74
#ISCELL
  logical_power universal_gnd *
  page60_i75
#ISCELL
  logical_power universal_gnd *
  page60_i76
#ISCELL
  logical_power universal_gnd *
  page60_i8
#CELL
  pure_quanta tdr_3p *
  page60_i9
